(kicad_pcb
	(version 20260206)
	(generator "pcbnew")
	(generator_version "10.0")
	(general
		(thickness 1.6)
		(legacy_teardrops no)
	)
	(paper "A4")
	(title_block
		(title "panther-plus-userver — 13130-1b_20150205.brd")
		(comment 1 "Honey Badger (Wiwynn) / footprints 520-527 of 1509")
	)
	(layers
		(0 "F.Cu" signal "TOP")
		(4 "In1.Cu" signal "L2")
		(6 "In2.Cu" signal "L3")
		(8 "In3.Cu" signal "L4")
		(10 "In4.Cu" signal "L5")
		(12 "In5.Cu" signal "L6")
		(14 "In6.Cu" signal "L7")
		(16 "In7.Cu" signal "L8")
		(18 "In8.Cu" signal "L9")
		(20 "In9.Cu" signal "L10")
		(22 "In10.Cu" signal "L11")
		(2 "B.Cu" signal "BOTTOM")
		(9 "F.Adhes" user "F.Adhesive")
		(11 "B.Adhes" user "B.Adhesive")
		(13 "F.Paste" user "Package Geometry/Pastemask Top")
		(15 "B.Paste" user "Package Geometry/Pastemask Bottom")
		(5 "F.SilkS" user "Ref Des/Silkscreen Top")
		(7 "B.SilkS" user "Ref Des/Silkscreen Bottom")
		(1 "F.Mask" user "Board Geometry/Soldermask Top")
		(3 "B.Mask" user "Board Geometry/Soldermask Bottom")
		(17 "Dwgs.User" user "User.Drawings")
		(19 "Cmts.User" user "User.Comments")
		(21 "Eco1.User" user "User.Eco1")
		(23 "Eco2.User" user "User.Eco2")
		(25 "Edge.Cuts" user "Board Geometry/Outline")
		(27 "Margin" user)
		(31 "F.CrtYd" user "Package Geometry/Place Bound Top")
		(29 "B.CrtYd" user "Package Geometry/Place Bound Bottom")
		(35 "F.Fab" user "Ref Des/Assembly Top")
		(33 "B.Fab" user "Ref Des/Assembly Bottom")
	)
	(footprint ""
		(layer "F.Cu")
		(at 54.737 -54.356)
		(property "Reference" "PR147"
			(at 0 0 0)
			(layer "F.SilkS")
			(hide yes)
			(effects
				(font
					(size 1.27 1.27)
				)
			)
		)
		(property "Value" "348KR2F-GP"
			(at 1.7907 -1.1176 0)
			(unlocked yes)
			(layer "F.Fab")
			(hide yes)
			(effects
				(font
					(size 1.016 1.016)
					(thickness 0.1524)
				)
			)
		)
		(property "Device Type" "R402H16"
			(at 1.7907 -2.6416 0)
			(unlocked yes)
			(layer "F.Fab")
			(hide yes)
			(effects
				(font
					(size 1.016 1.016)
					(thickness 0.1524)
				)
			)
		)
		(duplicate_pad_numbers_are_jumpers no)
		(fp_rect
			(start -0.381 0.8382)
			(end 0.381 -0.8382)
			(stroke
				(width 0)
				(type default)
			)
			(fill no)
			(layer "F.CrtYd")
		)
		(fp_rect
			(start -0.381 0.8382)
			(end 0.381 -0.8382)
			(stroke
				(width 0)
				(type default)
			)
			(fill no)
			(layer "F.Fab")
		)
		(pad "1" smd custom
			(at 0 -0.4318)
			(size 0.127 0.127)
			(layers "F.Cu" "F.Mask" "F.Paste")
			(net "VR_FB_P1V0_STBY")
			(options
				(clearance outline)
				(anchor circle)
			)
			(primitives
				(gr_poly
					(pts
						(arc
							(start -0.2032 -0.2794)
							(mid -0.239121 -0.264521)
							(end -0.254 -0.2286)
						)
						(arc
							(start -0.254 0.2286)
							(mid -0.239121 0.264521)
							(end -0.2032 0.2794)
						)
						(arc
							(start 0.2032 0.2794)
							(mid 0.239121 0.264521)
							(end 0.254 0.2286)
						)
						(arc
							(start 0.254 -0.2286)
							(mid 0.239121 -0.264521)
							(end 0.2032 -0.2794)
						)
					)
					(width 0)
					(fill yes)
				)
			)
		)
		(pad "2" smd custom
			(at 0 0.4318)
			(size 0.127 0.127)
			(layers "F.Cu" "F.Mask" "F.Paste")
			(net "AGND_P1V0_STBY")
			(options
				(clearance outline)
				(anchor circle)
			)
			(primitives
				(gr_poly
					(pts
						(arc
							(start -0.2032 -0.2794)
							(mid -0.239121 -0.264521)
							(end -0.254 -0.2286)
						)
						(arc
							(start -0.254 0.2286)
							(mid -0.239121 0.264521)
							(end -0.2032 0.2794)
						)
						(arc
							(start 0.2032 0.2794)
							(mid 0.239121 0.264521)
							(end 0.254 0.2286)
						)
						(arc
							(start 0.254 -0.2286)
							(mid 0.239121 -0.264521)
							(end 0.2032 -0.2794)
						)
					)
					(width 0)
					(fill yes)
				)
			)
		)
	)
	(footprint ""
		(layer "F.Cu")
		(at 11.3792 -54.0258 90)
		(property "Reference" "C56"
			(at 0 0 90)
			(layer "F.SilkS")
			(hide yes)
			(effects
				(font
					(size 1.27 1.27)
				)
			)
		)
		(property "Value" "SCD01U16V2KX-3GP"
			(at 1.1811 -2.7051 90)
			(unlocked yes)
			(layer "F.Fab")
			(hide yes)
			(effects
				(font
					(size 1.016 1.016)
					(thickness 0.1524)
				)
			)
		)
		(property "Device Type" "C402H22"
			(at 1.1811 -4.2291 90)
			(unlocked yes)
			(layer "F.Fab")
			(hide yes)
			(effects
				(font
					(size 1.016 1.016)
					(thickness 0.1524)
				)
			)
		)
		(duplicate_pad_numbers_are_jumpers no)
		(fp_rect
			(start -0.381 0.7366)
			(end 0.381 -0.7366)
			(stroke
				(width 0)
				(type default)
			)
			(fill no)
			(layer "F.CrtYd")
		)
		(fp_rect
			(start -0.381 0.7366)
			(end 0.381 -0.7366)
			(stroke
				(width 0)
				(type default)
			)
			(fill no)
			(layer "F.Fab")
		)
		(pad "1" smd custom
			(at 0 -0.4572 90)
			(size 0.1143 0.1143)
			(layers "F.Cu" "F.Mask" "F.Paste")
			(net "SATA3_RX_DP1")
			(options
				(clearance outline)
				(anchor circle)
			)
			(primitives
				(gr_poly
					(pts
						(arc
							(start -0.254 -0.1778)
							(mid -0.239121 -0.213721)
							(end -0.2032 -0.2286)
						)
						(arc
							(start 0.2032 -0.2286)
							(mid 0.239121 -0.213721)
							(end 0.254 -0.1778)
						)
						(arc
							(start 0.254 0.1778)
							(mid 0.239121 0.213721)
							(end 0.2032 0.2286)
						)
						(arc
							(start -0.2032 0.2286)
							(mid -0.239121 0.213721)
							(end -0.254 0.1778)
						)
					)
					(width 0)
					(fill yes)
				)
			)
		)
		(pad "2" smd custom
			(at 0 0.4572 90)
			(size 0.1143 0.1143)
			(layers "F.Cu" "F.Mask" "F.Paste")
			(net "P2E_CPU_NGFF_C_RX_DN12")
			(options
				(clearance outline)
				(anchor circle)
			)
			(primitives
				(gr_poly
					(pts
						(arc
							(start -0.254 -0.1778)
							(mid -0.239121 -0.213721)
							(end -0.2032 -0.2286)
						)
						(arc
							(start 0.2032 -0.2286)
							(mid 0.239121 -0.213721)
							(end 0.254 -0.1778)
						)
						(arc
							(start 0.254 0.1778)
							(mid 0.239121 0.213721)
							(end 0.2032 0.2286)
						)
						(arc
							(start -0.2032 0.2286)
							(mid -0.239121 0.213721)
							(end -0.254 0.1778)
						)
					)
					(width 0)
					(fill yes)
				)
			)
		)
	)
	(footprint ""
		(layer "F.Cu")
		(at 203.073 -54.0512 90)
		(property "Reference" "PC180"
			(at 0 0 90)
			(layer "F.SilkS")
			(hide yes)
			(effects
				(font
					(size 1.27 1.27)
				)
			)
		)
		(property "Value" "SC100U6D3V0MX-2GP"
			(at -2.3368 -3.5052 90)
			(unlocked yes)
			(layer "F.Fab")
			(hide yes)
			(effects
				(font
					(size 1.016 1.016)
					(thickness 0.1524)
				)
			)
		)
		(property "Device Type" "C1210H107"
			(at -2.3368 -5.0292 90)
			(unlocked yes)
			(layer "F.Fab")
			(hide yes)
			(effects
				(font
					(size 1.016 1.016)
					(thickness 0.1524)
				)
			)
		)
		(duplicate_pad_numbers_are_jumpers no)
		(fp_rect
			(start -1.4986 1.9685)
			(end 1.4986 -1.9685)
			(stroke
				(width 0)
				(type default)
			)
			(fill no)
			(layer "F.CrtYd")
		)
		(fp_rect
			(start -1.4986 1.9685)
			(end 1.4986 -1.9685)
			(stroke
				(width 0)
				(type default)
			)
			(fill no)
			(layer "F.Fab")
		)
		(pad "1" smd rect
			(at 0 -1.2446 90)
			(size 2.7432 1.1938)
			(layers "F.Cu" "F.Mask" "F.Paste")
			(net "PV_VDDR")
		)
		(pad "2" smd rect
			(at 0 1.2446 90)
			(size 2.7432 1.1938)
			(layers "F.Cu" "F.Mask" "F.Paste")
			(net "GND")
		)
	)
	(footprint ""
		(layer "F.Cu")
		(at 157.226 -32.639 90)
		(property "Reference" "R142"
			(at 0 0 90)
			(layer "F.SilkS")
			(hide yes)
			(effects
				(font
					(size 1.27 1.27)
				)
			)
		)
		(property "Value" "0R2J-2-GP"
			(at 0.064008 -3.993896 90)
			(unlocked yes)
			(layer "F.Fab")
			(hide yes)
			(effects
				(font
					(size 1.016 1.016)
					(thickness 0.1524)
				)
			)
		)
		(property "Device Type" "R402H16"
			(at 0.064008 -5.517896 90)
			(unlocked yes)
			(layer "F.Fab")
			(hide yes)
			(effects
				(font
					(size 1.016 1.016)
					(thickness 0.1524)
				)
			)
		)
		(duplicate_pad_numbers_are_jumpers no)
		(fp_rect
			(start -0.381 0.8382)
			(end 0.381 -0.8382)
			(stroke
				(width 0)
				(type default)
			)
			(fill no)
			(layer "F.CrtYd")
		)
		(fp_rect
			(start -0.381 0.8382)
			(end 0.381 -0.8382)
			(stroke
				(width 0)
				(type default)
			)
			(fill no)
			(layer "F.Fab")
		)
		(pad "1" smd custom
			(at 0 -0.4318 90)
			(size 0.127 0.127)
			(layers "F.Cu" "F.Mask" "F.Paste")
			(net "READY_R#")
			(options
				(clearance outline)
				(anchor circle)
			)
			(primitives
				(gr_poly
					(pts
						(arc
							(start -0.2032 -0.2794)
							(mid -0.239121 -0.264521)
							(end -0.254 -0.2286)
						)
						(arc
							(start -0.254 0.2286)
							(mid -0.239121 0.264521)
							(end -0.2032 0.2794)
						)
						(arc
							(start 0.2032 0.2794)
							(mid 0.239121 0.264521)
							(end 0.254 0.2286)
						)
						(arc
							(start 0.254 -0.2286)
							(mid 0.239121 -0.264521)
							(end 0.2032 -0.2794)
						)
					)
					(width 0)
					(fill yes)
				)
			)
		)
		(pad "2" smd custom
			(at 0 0.4318 90)
			(size 0.127 0.127)
			(layers "F.Cu" "F.Mask" "F.Paste")
			(net "FPGA_READY#")
			(options
				(clearance outline)
				(anchor circle)
			)
			(primitives
				(gr_poly
					(pts
						(arc
							(start -0.2032 -0.2794)
							(mid -0.239121 -0.264521)
							(end -0.254 -0.2286)
						)
						(arc
							(start -0.254 0.2286)
							(mid -0.239121 0.264521)
							(end -0.2032 0.2794)
						)
						(arc
							(start 0.2032 0.2794)
							(mid 0.239121 0.264521)
							(end 0.254 0.2286)
						)
						(arc
							(start 0.254 -0.2286)
							(mid 0.239121 -0.264521)
							(end 0.2032 -0.2794)
						)
					)
					(width 0)
					(fill yes)
				)
			)
		)
	)
	(footprint ""
		(layer "F.Cu")
		(at 49.4284 -22.987 180)
		(property "Reference" "R440"
			(at 0 0 180)
			(layer "F.SilkS")
			(hide yes)
			(effects
				(font
					(size 1.27 1.27)
				)
			)
		)
		(property "Value" "4K7R2F-GP"
			(at 1.7907 -1.1176 180)
			(unlocked yes)
			(layer "F.Fab")
			(hide yes)
			(effects
				(font
					(size 1.016 1.016)
					(thickness 0.1524)
				)
			)
		)
		(property "Device Type" "R402H16"
			(at 1.7907 -2.6416 180)
			(unlocked yes)
			(layer "F.Fab")
			(hide yes)
			(effects
				(font
					(size 1.016 1.016)
					(thickness 0.1524)
				)
			)
		)
		(duplicate_pad_numbers_are_jumpers no)
		(fp_rect
			(start -0.381 0.8382)
			(end 0.381 -0.8382)
			(stroke
				(width 0)
				(type default)
			)
			(fill no)
			(layer "F.CrtYd")
		)
		(fp_rect
			(start -0.381 0.8382)
			(end 0.381 -0.8382)
			(stroke
				(width 0)
				(type default)
			)
			(fill no)
			(layer "F.Fab")
		)
		(pad "1" smd custom
			(at 0 -0.4318 180)
			(size 0.127 0.127)
			(layers "F.Cu" "F.Mask" "F.Paste")
			(net "P3V3")
			(options
				(clearance outline)
				(anchor circle)
			)
			(primitives
				(gr_poly
					(pts
						(arc
							(start -0.2032 -0.2794)
							(mid -0.239121 -0.264521)
							(end -0.254 -0.2286)
						)
						(arc
							(start -0.254 0.2286)
							(mid -0.239121 0.264521)
							(end -0.2032 0.2794)
						)
						(arc
							(start 0.2032 0.2794)
							(mid 0.239121 0.264521)
							(end 0.254 0.2286)
						)
						(arc
							(start 0.254 -0.2286)
							(mid 0.239121 -0.264521)
							(end 0.2032 -0.2794)
						)
					)
					(width 0)
					(fill yes)
				)
			)
		)
		(pad "2" smd custom
			(at 0 0.4318 180)
			(size 0.127 0.127)
			(layers "F.Cu" "F.Mask" "F.Paste")
			(net "CLKBUFF_OE4#")
			(options
				(clearance outline)
				(anchor circle)
			)
			(primitives
				(gr_poly
					(pts
						(arc
							(start -0.2032 -0.2794)
							(mid -0.239121 -0.264521)
							(end -0.254 -0.2286)
						)
						(arc
							(start -0.254 0.2286)
							(mid -0.239121 0.264521)
							(end -0.2032 0.2794)
						)
						(arc
							(start 0.2032 0.2794)
							(mid 0.239121 0.264521)
							(end 0.254 0.2286)
						)
						(arc
							(start 0.254 -0.2286)
							(mid 0.239121 -0.264521)
							(end 0.2032 -0.2794)
						)
					)
					(width 0)
					(fill yes)
				)
			)
		)
	)
	(footprint ""
		(layer "F.Cu")
		(at 109.601 -64.643 -90)
		(property "Reference" "U4"
			(at 0 0 270)
			(layer "F.SilkS")
			(hide yes)
			(effects
				(font
					(size 1.27 1.27)
				)
			)
		)
		(property "Value" "SN74LVC1G07DCKRG4-2-GP"
			(at -2.3368 -8.6868 270)
			(unlocked yes)
			(layer "F.Fab")
			(hide yes)
			(effects
				(font
					(size 1.016 1.016)
					(thickness 0.1524)
				)
			)
		)
		(property "Device Type" "SC70-5H44"
			(at -2.3114 -10.414 270)
			(unlocked yes)
			(layer "F.Fab")
			(hide yes)
			(effects
				(font
					(size 1.016 1.016)
					(thickness 0.1524)
				)
			)
		)
		(duplicate_pad_numbers_are_jumpers no)
		(fp_line
			(start -1.0033 0.3302)
			(end -1.0033 -0.3302)
			(stroke
				(width 0.1524)
				(type default)
			)
			(layer "F.SilkS")
		)
		(fp_line
			(start 1.0033 0.3302)
			(end -1.0033 0.3302)
			(stroke
				(width 0.1524)
				(type default)
			)
			(layer "F.SilkS")
		)
		(fp_line
			(start -1.0033 -0.3302)
			(end 1.0033 -0.3302)
			(stroke
				(width 0.1524)
				(type default)
			)
			(layer "F.SilkS")
		)
		(fp_line
			(start 1.0033 -0.3302)
			(end 1.0033 0.3302)
			(stroke
				(width 0.1524)
				(type default)
			)
			(layer "F.SilkS")
		)
		(fp_poly
			(pts
				(xy -1.0033 1.4859) (xy -1.0033 0.8001) (xy -1.1811 0.8001) (xy -1.1811 -0.8001) (xy -1.0033 -0.8001)
				(xy -1.0033 -1.4859) (xy 1.0033 -1.4859) (xy 1.0033 -0.8001) (xy 1.1811 -0.8001) (xy 1.1811 0.8001)
				(xy 1.0033 0.8001) (xy 1.0033 1.4859) (xy 0.2921 1.4859) (xy 0.2921 0.8001) (xy -0.2921 0.8001)
				(xy -0.2921 1.4859)
			)
			(stroke
				(width 0)
				(type default)
			)
			(fill no)
			(layer "F.CrtYd")
		)
		(fp_poly
			(pts
				(xy -1.0033 1.4859) (xy -1.0033 0.8001) (xy -1.1811 0.8001) (xy -1.1811 -0.8001) (xy -1.0033 -0.8001)
				(xy -1.0033 -1.4859) (xy 1.0033 -1.4859) (xy 1.0033 -0.8001) (xy 1.1811 -0.8001) (xy 1.1811 0.8001)
				(xy 1.0033 0.8001) (xy 1.0033 1.4859) (xy 0.2921 1.4859) (xy 0.2921 0.8001) (xy -0.2921 0.8001)
				(xy -0.2921 1.4859)
			)
			(stroke
				(width 0)
				(type default)
			)
			(fill no)
			(layer "F.Fab")
		)
		(pad "1" smd rect
			(at 0.65024 -0.93472 270)
			(size 0.3556 0.762)
			(layers "F.Cu" "F.Mask" "F.Paste")
			(net "Net_445")
		)
		(pad "2" smd rect
			(at 0 -0.93472 270)
			(size 0.3556 0.762)
			(layers "F.Cu" "F.Mask" "F.Paste")
			(net "DDR3_DRAM_PWROK")
		)
		(pad "3" smd rect
			(at -0.65024 -0.93472 270)
			(size 0.3556 0.762)
			(layers "F.Cu" "F.Mask" "F.Paste")
			(net "GND")
		)
		(pad "4" smd rect
			(at -0.65024 0.93472 270)
			(size 0.3556 0.762)
			(layers "F.Cu" "F.Mask" "F.Paste")
			(net "M_DRAM_PWROK")
		)
		(pad "5" smd rect
			(at 0.65024 0.93472 270)
			(size 0.3556 0.762)
			(layers "F.Cu" "F.Mask" "F.Paste")
			(net "P3V3_STBY")
		)
	)
	(footprint ""
		(layer "F.Cu")
		(at 57.277 -48.514 90)
		(property "Reference" "PC100"
			(at 0 0 90)
			(layer "F.SilkS")
			(hide yes)
			(effects
				(font
					(size 1.27 1.27)
				)
			)
		)
		(property "Value" "SC22U6D3V5MX-2GP"
			(at 0 -4.9022 90)
			(unlocked yes)
			(layer "F.Fab")
			(hide yes)
			(effects
				(font
					(size 1.016 1.016)
					(thickness 0.1524)
				)
			)
		)
		(property "Device Type" "C805H58"
			(at 0 -6.8072 90)
			(unlocked yes)
			(layer "F.Fab")
			(hide yes)
			(effects
				(font
					(size 1.016 1.016)
					(thickness 0.1524)
				)
			)
		)
		(duplicate_pad_numbers_are_jumpers no)
		(fp_line
			(start 0.6096 0)
			(end -0.6096 0)
			(stroke
				(width 0.3048)
				(type default)
			)
			(layer "F.SilkS")
		)
		(fp_poly
			(pts
				(xy -0.9017 1.4351) (xy 0.9017 1.4351) (xy 0.9017 -1.4351) (xy -0.9017 -1.4351)
			)
			(stroke
				(width 0)
				(type default)
			)
			(fill no)
			(layer "F.CrtYd")
		)
		(fp_poly
			(pts
				(xy 0.9017 1.4351) (xy 0.9017 -1.4351) (xy -0.9017 -1.4351) (xy -0.9017 1.4351)
			)
			(stroke
				(width 0)
				(type default)
			)
			(fill no)
			(layer "F.Fab")
		)
		(pad "1" smd rect
			(at 0 -0.8382 90)
			(size 1.5494 0.9398)
			(layers "F.Cu" "F.Mask" "F.Paste")
			(net "VR_PVIN_P1V0_STBY")
		)
		(pad "2" smd rect
			(at 0 0.8382 90)
			(size 1.5494 0.9398)
			(layers "F.Cu" "F.Mask" "F.Paste")
			(net "GND")
		)
	)
	(footprint ""
		(layer "F.Cu")
		(at 15.8496 -57.6072 -90)
		(property "Reference" "PR62"
			(at 0 0 270)
			(layer "F.SilkS")
			(hide yes)
			(effects
				(font
					(size 1.27 1.27)
				)
			)
		)
		(property "Value" "0R2J-2-GP"
			(at 1.7907 -1.1176 270)
			(unlocked yes)
			(layer "F.Fab")
			(hide yes)
			(effects
				(font
					(size 1.016 1.016)
					(thickness 0.1524)
				)
			)
		)
		(property "Device Type" "R402H16"
			(at 1.7907 -2.6416 270)
			(unlocked yes)
			(layer "F.Fab")
			(hide yes)
			(effects
				(font
					(size 1.016 1.016)
					(thickness 0.1524)
				)
			)
		)
		(duplicate_pad_numbers_are_jumpers no)
		(fp_rect
			(start -0.381 0.8382)
			(end 0.381 -0.8382)
			(stroke
				(width 0)
				(type default)
			)
			(fill no)
			(layer "F.CrtYd")
		)
		(fp_rect
			(start -0.381 0.8382)
			(end 0.381 -0.8382)
			(stroke
				(width 0)
				(type default)
			)
			(fill no)
			(layer "F.Fab")
		)
		(pad "1" smd custom
			(at 0 -0.4318 270)
			(size 0.127 0.127)
			(layers "F.Cu" "F.Mask" "F.Paste")
			(net "PVCC_PVNN_EN_R")
			(options
				(clearance outline)
				(anchor circle)
			)
			(primitives
				(gr_poly
					(pts
						(arc
							(start -0.2032 -0.2794)
							(mid -0.239121 -0.264521)
							(end -0.254 -0.2286)
						)
						(arc
							(start -0.254 0.2286)
							(mid -0.239121 0.264521)
							(end -0.2032 0.2794)
						)
						(arc
							(start 0.2032 0.2794)
							(mid 0.239121 0.264521)
							(end 0.254 0.2286)
						)
						(arc
							(start 0.254 -0.2286)
							(mid 0.239121 -0.264521)
							(end 0.2032 -0.2794)
						)
					)
					(width 0)
					(fill yes)
				)
			)
		)
		(pad "2" smd custom
			(at 0 0.4318 270)
			(size 0.127 0.127)
			(layers "F.Cu" "F.Mask" "F.Paste")
			(net "PWRGD_PVTT_PG")
			(options
				(clearance outline)
				(anchor circle)
			)
			(primitives
				(gr_poly
					(pts
						(arc
							(start -0.2032 -0.2794)
							(mid -0.239121 -0.264521)
							(end -0.254 -0.2286)
						)
						(arc
							(start -0.254 0.2286)
							(mid -0.239121 0.264521)
							(end -0.2032 0.2794)
						)
						(arc
							(start 0.2032 0.2794)
							(mid 0.239121 0.264521)
							(end 0.254 0.2286)
						)
						(arc
							(start 0.254 -0.2286)
							(mid 0.239121 -0.264521)
							(end 0.2032 -0.2794)
						)
					)
					(width 0)
					(fill yes)
				)
			)
		)
	)
)
